(kicad_pcb
	(version 20260206)
	(generator "pcbnew")
	(generator_version "10.0")
	(general
		(thickness 1.6)
		(legacy_teardrops no)
	)
	(paper "A4")
	(title_block
		(title "01162023_DA0F0TEBIF0_F0T_Expander_BD_F_brd_V02_OCP.brd")
		(comment 1 "Grand Teton / footprints 8693-8699 of 9728")
	)
	(layers
		(0 "F.Cu" signal "TOP")
		(4 "In1.Cu" signal "GND")
		(6 "In2.Cu" signal "VCC")
		(8 "In3.Cu" signal "VCC1")
		(10 "In4.Cu" signal "GND1")
		(12 "In5.Cu" signal "IN1")
		(14 "In6.Cu" signal "GND2")
		(16 "In7.Cu" signal "IN2")
		(18 "In8.Cu" signal "GND3")
		(20 "In9.Cu" signal "IN3")
		(22 "In10.Cu" signal "GND4")
		(24 "In11.Cu" signal "IN4")
		(26 "In12.Cu" signal "GND5")
		(28 "In13.Cu" signal "IN5")
		(30 "In14.Cu" signal "GND6")
		(32 "In15.Cu" signal "IN6")
		(34 "In16.Cu" signal "GND7")
		(2 "B.Cu" signal "BOTTOM")
		(9 "F.Adhes" user "F.Adhesive")
		(11 "B.Adhes" user "B.Adhesive")
		(13 "F.Paste" user "Package Geometry/Pastemask Top")
		(15 "B.Paste" user "Package Geometry/Pastemask Bottom")
		(5 "F.SilkS" user "Ref Des/Silkscreen Top")
		(7 "B.SilkS" user "Ref Des/Silkscreen Bottom")
		(1 "F.Mask" user "Board Geometry/Soldermask Top")
		(3 "B.Mask" user "Board Geometry/Soldermask Bottom")
		(17 "Dwgs.User" user "User.Drawings")
		(19 "Cmts.User" user "User.Comments")
		(21 "Eco1.User" user "User.Eco1")
		(23 "Eco2.User" user "User.Eco2")
		(25 "Edge.Cuts" user "Board Geometry/Outline")
		(27 "Margin" user)
		(31 "F.CrtYd" user "Package Geometry/Place Bound Top")
		(29 "B.CrtYd" user "Package Geometry/Place Bound Bottom")
		(35 "F.Fab" user "Ref Des/Assembly Top")
		(33 "B.Fab" user "Ref Des/Assembly Bottom")
	)
	(footprint ""
		(layer "B.Cu")
		(at 213.832694 -217.270838 180)
		(property "Reference" "R4862"
			(at 0 0 0)
			(layer "B.SilkS")
			(hide yes)
			(effects
				(font
					(size 1.27 1.27)
				)
				(justify mirror)
			)
		)
		(property "Value" ""
			(at 0 0 0)
			(layer "B.Fab")
			(effects
				(font
					(size 1.27 1.27)
				)
				(justify mirror)
			)
		)
		(duplicate_pad_numbers_are_jumpers no)
		(fp_line
			(start 0.7874 0.4064)
			(end 0.7874 -0.4064)
			(stroke
				(width 0.1524)
				(type default)
			)
			(layer "B.SilkS")
		)
		(fp_line
			(start 0.7874 -0.4064)
			(end -0.7874 -0.4064)
			(stroke
				(width 0.1524)
				(type default)
			)
			(layer "B.SilkS")
		)
		(fp_line
			(start -0.7874 0.4064)
			(end 0.7874 0.4064)
			(stroke
				(width 0.1524)
				(type default)
			)
			(layer "B.SilkS")
		)
		(fp_line
			(start -0.7874 -0.4064)
			(end -0.7874 0.4064)
			(stroke
				(width 0.1524)
				(type default)
			)
			(layer "B.SilkS")
		)
		(fp_line
			(start 0.67945 0.3048)
			(end 0.67945 -0.305054)
			(stroke
				(width 0.1)
				(type default)
			)
			(layer "B.Fab")
		)
		(fp_line
			(start 0.67945 -0.305054)
			(end 0.12065 -0.305054)
			(stroke
				(width 0.1)
				(type default)
			)
			(layer "B.Fab")
		)
		(fp_line
			(start 0.12065 0.3048)
			(end 0.67945 0.3048)
			(stroke
				(width 0.1)
				(type default)
			)
			(layer "B.Fab")
		)
		(fp_line
			(start 0.12065 0.2794)
			(end 0.12065 0.3048)
			(stroke
				(width 0.1)
				(type default)
			)
			(layer "B.Fab")
		)
		(fp_line
			(start 0.12065 -0.2794)
			(end -0.12065 -0.2794)
			(stroke
				(width 0.1)
				(type default)
			)
			(layer "B.Fab")
		)
		(fp_line
			(start 0.12065 -0.305054)
			(end 0.12065 -0.2794)
			(stroke
				(width 0.1)
				(type default)
			)
			(layer "B.Fab")
		)
		(fp_line
			(start -0.120396 0.3048)
			(end -0.120396 0.2794)
			(stroke
				(width 0.1)
				(type default)
			)
			(layer "B.Fab")
		)
		(fp_line
			(start -0.120396 0.2794)
			(end 0.12065 0.2794)
			(stroke
				(width 0.1)
				(type default)
			)
			(layer "B.Fab")
		)
		(fp_line
			(start -0.12065 -0.2794)
			(end -0.12065 -0.3048)
			(stroke
				(width 0.1)
				(type default)
			)
			(layer "B.Fab")
		)
		(fp_line
			(start -0.12065 -0.3048)
			(end -0.67945 -0.3048)
			(stroke
				(width 0.1)
				(type default)
			)
			(layer "B.Fab")
		)
		(fp_line
			(start -0.67945 0.3048)
			(end -0.120396 0.3048)
			(stroke
				(width 0.1)
				(type default)
			)
			(layer "B.Fab")
		)
		(fp_line
			(start -0.67945 -0.3048)
			(end -0.67945 0.3048)
			(stroke
				(width 0.1)
				(type default)
			)
			(layer "B.Fab")
		)
		(pad "1" smd circle
			(at 0.40005 0)
			(size 0 0)
			(layers "B.Cu" "B.Mask" "B.Paste")
			(net "P1V2_AUX")
		)
		(pad "2" smd circle
			(at -0.40005 0)
			(size 0 0)
			(layers "B.Cu" "B.Mask" "B.Paste")
			(net "PECI_VDD")
		)
	)
	(footprint ""
		(layer "B.Cu")
		(at 257.322574 -220.924374 90)
		(property "Reference" "R3486"
			(at 0 0 90)
			(layer "B.SilkS")
			(hide yes)
			(effects
				(font
					(size 1.27 1.27)
				)
				(justify mirror)
			)
		)
		(property "Value" ""
			(at 0 0 90)
			(layer "B.Fab")
			(effects
				(font
					(size 1.27 1.27)
				)
				(justify mirror)
			)
		)
		(duplicate_pad_numbers_are_jumpers no)
		(fp_line
			(start 0.7874 -0.4064)
			(end -0.7874 -0.4064)
			(stroke
				(width 0.1524)
				(type default)
			)
			(layer "B.SilkS")
		)
		(fp_line
			(start -0.7874 -0.4064)
			(end -0.7874 0.4064)
			(stroke
				(width 0.1524)
				(type default)
			)
			(layer "B.SilkS")
		)
		(fp_line
			(start 0.7874 0.4064)
			(end 0.7874 -0.4064)
			(stroke
				(width 0.1524)
				(type default)
			)
			(layer "B.SilkS")
		)
		(fp_line
			(start -0.7874 0.4064)
			(end 0.7874 0.4064)
			(stroke
				(width 0.1524)
				(type default)
			)
			(layer "B.SilkS")
		)
		(fp_line
			(start 0.67945 -0.305054)
			(end 0.12065 -0.305054)
			(stroke
				(width 0.1)
				(type default)
			)
			(layer "B.Fab")
		)
		(fp_line
			(start 0.12065 -0.305054)
			(end 0.12065 -0.2794)
			(stroke
				(width 0.1)
				(type default)
			)
			(layer "B.Fab")
		)
		(fp_line
			(start -0.12065 -0.3048)
			(end -0.67945 -0.3048)
			(stroke
				(width 0.1)
				(type default)
			)
			(layer "B.Fab")
		)
		(fp_line
			(start -0.67945 -0.3048)
			(end -0.67945 0.3048)
			(stroke
				(width 0.1)
				(type default)
			)
			(layer "B.Fab")
		)
		(fp_line
			(start 0.12065 -0.2794)
			(end -0.12065 -0.2794)
			(stroke
				(width 0.1)
				(type default)
			)
			(layer "B.Fab")
		)
		(fp_line
			(start -0.12065 -0.2794)
			(end -0.12065 -0.3048)
			(stroke
				(width 0.1)
				(type default)
			)
			(layer "B.Fab")
		)
		(fp_line
			(start 0.12065 0.2794)
			(end 0.12065 0.3048)
			(stroke
				(width 0.1)
				(type default)
			)
			(layer "B.Fab")
		)
		(fp_line
			(start -0.120396 0.2794)
			(end 0.12065 0.2794)
			(stroke
				(width 0.1)
				(type default)
			)
			(layer "B.Fab")
		)
		(fp_line
			(start 0.67945 0.3048)
			(end 0.67945 -0.305054)
			(stroke
				(width 0.1)
				(type default)
			)
			(layer "B.Fab")
		)
		(fp_line
			(start 0.12065 0.3048)
			(end 0.67945 0.3048)
			(stroke
				(width 0.1)
				(type default)
			)
			(layer "B.Fab")
		)
		(fp_line
			(start -0.120396 0.3048)
			(end -0.120396 0.2794)
			(stroke
				(width 0.1)
				(type default)
			)
			(layer "B.Fab")
		)
		(fp_line
			(start -0.67945 0.3048)
			(end -0.120396 0.3048)
			(stroke
				(width 0.1)
				(type default)
			)
			(layer "B.Fab")
		)
		(pad "1" smd circle
			(at 0.40005 0 270)
			(size 0 0)
			(layers "B.Cu" "B.Mask" "B.Paste")
			(net "P1V8_PEX")
		)
		(pad "2" smd circle
			(at -0.40005 0 270)
			(size 0 0)
			(layers "B.Cu" "B.Mask" "B.Paste")
			(net "SPI_PEX2_SDIO3_R1")
		)
	)
	(footprint ""
		(layer "B.Cu")
		(at 185.349134 -115.613434 -90)
		(property "Reference" "U23"
			(at 0.268986 4.072382 0)
			(unlocked yes)
			(layer "B.SilkS")
			(effects
				(font
					(size 0.7874 0.5842)
					(thickness 0.1524)
				)
				(justify mirror)
			)
		)
		(property "Value" ""
			(at 0 0 90)
			(layer "B.Fab")
			(effects
				(font
					(size 1.27 1.27)
				)
				(justify mirror)
			)
		)
		(duplicate_pad_numbers_are_jumpers no)
		(fp_line
			(start -1.3462 1.1938)
			(end -1.3462 -1.1938)
			(stroke
				(width 0.1524)
				(type default)
			)
			(layer "B.SilkS")
		)
		(fp_line
			(start 1.3462 1.1938)
			(end -1.3462 1.1938)
			(stroke
				(width 0.1524)
				(type default)
			)
			(layer "B.SilkS")
		)
		(fp_line
			(start -1.3462 -1.1938)
			(end 1.3462 -1.1938)
			(stroke
				(width 0.1524)
				(type default)
			)
			(layer "B.SilkS")
		)
		(fp_line
			(start 1.3462 -1.1938)
			(end 1.3462 1.1684)
			(stroke
				(width 0.1524)
				(type default)
			)
			(layer "B.SilkS")
		)
		(fp_poly
			(pts
				(xy 1.447038 -0.760476) (xy 2.052066 -0.457962) (xy 2.052066 -1.06299)
			)
			(stroke
				(width 0)
				(type default)
			)
			(fill yes)
			(layer "B.SilkS")
		)
		(fp_line
			(start -0.674878 1.124966)
			(end -0.674878 -1.124966)
			(stroke
				(width 0.1)
				(type default)
			)
			(layer "B.Fab")
		)
		(fp_line
			(start 0.674878 1.124966)
			(end -0.674878 1.124966)
			(stroke
				(width 0.1)
				(type default)
			)
			(layer "B.Fab")
		)
		(fp_line
			(start -0.674878 -1.124966)
			(end 0.674878 -1.124966)
			(stroke
				(width 0.1)
				(type default)
			)
			(layer "B.Fab")
		)
		(fp_line
			(start 0.674878 -1.124966)
			(end 0.674878 1.124966)
			(stroke
				(width 0.1)
				(type default)
			)
			(layer "B.Fab")
		)
		(fp_poly
			(pts
				(xy 1.447038 -0.760476) (xy 2.052066 -0.457962) (xy 2.052066 -1.06299)
			)
			(stroke
				(width 0)
				(type default)
			)
			(fill yes)
			(layer "B.Fab")
		)
		(pad "1" smd rect
			(at 0.899922 -0.750062 90)
			(size 0.6096 0.6096)
			(layers "B.Cu" "B.Mask" "B.Paste")
			(net "NIC3_AUX_PWR_EN_R")
		)
		(pad "2" smd rect
			(at 0.899922 0)
			(size 0.4064 0.6096)
			(layers "B.Cu" "B.Mask" "B.Paste")
			(net "RST_SMB_NIC3_MUX_N")
		)
		(pad "3" smd rect
			(at 0.899922 0.750062 90)
			(size 0.6096 0.6096)
			(layers "B.Cu" "B.Mask" "B.Paste")
			(net "GND")
		)
		(pad "4" smd rect
			(at -0.899922 0.750062 90)
			(size 0.6096 0.6096)
			(layers "B.Cu" "B.Mask" "B.Paste")
			(net "RST_SMB_NIC3_MUX_ISO_N")
		)
		(pad "5" smd rect
			(at -0.899922 -0.750062 90)
			(size 0.6096 0.6096)
			(layers "B.Cu" "B.Mask" "B.Paste")
			(net "P3V3_AUX")
		)
	)
	(footprint ""
		(layer "B.Cu")
		(at 408.451304 -305.399948 -90)
		(property "Reference" "C3495"
			(at 0 0 90)
			(layer "B.SilkS")
			(hide yes)
			(effects
				(font
					(size 1.27 1.27)
				)
				(justify mirror)
			)
		)
		(property "Value" ""
			(at 0 0 90)
			(layer "B.Fab")
			(effects
				(font
					(size 1.27 1.27)
				)
				(justify mirror)
			)
		)
		(duplicate_pad_numbers_are_jumpers no)
		(fp_line
			(start -0.299974 0.150114)
			(end 0.299974 0.150114)
			(stroke
				(width 0.1)
				(type default)
			)
			(layer "B.Fab")
		)
		(fp_line
			(start 0.299974 0.150114)
			(end 0.299974 -0.150114)
			(stroke
				(width 0.1)
				(type default)
			)
			(layer "B.Fab")
		)
		(fp_line
			(start -0.299974 -0.150114)
			(end -0.299974 0.150114)
			(stroke
				(width 0.1)
				(type default)
			)
			(layer "B.Fab")
		)
		(fp_line
			(start 0.299974 -0.150114)
			(end -0.299974 -0.150114)
			(stroke
				(width 0.1)
				(type default)
			)
			(layer "B.Fab")
		)
		(pad "1" smd rect
			(at 0.2667 0 90)
			(size 0.3048 0.381)
			(layers "B.Cu" "B.Mask" "B.Paste")
			(net "P1V25_SERDES_VDDPLL_PEX3")
		)
		(pad "2" smd rect
			(at -0.2667 0 90)
			(size 0.3048 0.381)
			(layers "B.Cu" "B.Mask" "B.Paste")
			(net "GND")
		)
	)
	(footprint ""
		(layer "B.Cu")
		(at 365.34344 -308.613556 90)
		(property "Reference" "C4372"
			(at 0 0 90)
			(layer "B.SilkS")
			(hide yes)
			(effects
				(font
					(size 1.27 1.27)
				)
				(justify mirror)
			)
		)
		(property "Value" ""
			(at 0 0 90)
			(layer "B.Fab")
			(effects
				(font
					(size 1.27 1.27)
				)
				(justify mirror)
			)
		)
		(duplicate_pad_numbers_are_jumpers no)
		(fp_line
			(start 1.2954 -0.5842)
			(end -1.2954 -0.5842)
			(stroke
				(width 0.1524)
				(type default)
			)
			(layer "B.SilkS")
		)
		(fp_line
			(start -1.2954 -0.5842)
			(end -1.2954 0.5842)
			(stroke
				(width 0.1524)
				(type default)
			)
			(layer "B.SilkS")
		)
		(fp_line
			(start 1.2954 0.5842)
			(end 1.2954 -0.5842)
			(stroke
				(width 0.1524)
				(type default)
			)
			(layer "B.SilkS")
		)
		(fp_line
			(start -1.2954 0.5842)
			(end 1.2954 0.5842)
			(stroke
				(width 0.1524)
				(type default)
			)
			(layer "B.SilkS")
		)
		(fp_line
			(start 0.8636 -0.4572)
			(end -0.8636 -0.4572)
			(stroke
				(width 0.1)
				(type default)
			)
			(layer "B.Fab")
		)
		(fp_line
			(start -0.8636 -0.4572)
			(end -0.8636 -0.4064)
			(stroke
				(width 0.1)
				(type default)
			)
			(layer "B.Fab")
		)
		(fp_line
			(start 1.1938 -0.4064)
			(end 0.8636 -0.4064)
			(stroke
				(width 0.1)
				(type default)
			)
			(layer "B.Fab")
		)
		(fp_line
			(start 0.8636 -0.4064)
			(end 0.8636 -0.4572)
			(stroke
				(width 0.1)
				(type default)
			)
			(layer "B.Fab")
		)
		(fp_line
			(start -0.8636 -0.4064)
			(end -1.1938 -0.4064)
			(stroke
				(width 0.1)
				(type default)
			)
			(layer "B.Fab")
		)
		(fp_line
			(start -1.1938 -0.4064)
			(end -1.1938 0.4064)
			(stroke
				(width 0.1)
				(type default)
			)
			(layer "B.Fab")
		)
		(fp_line
			(start 1.1938 0.4064)
			(end 1.1938 -0.4064)
			(stroke
				(width 0.1)
				(type default)
			)
			(layer "B.Fab")
		)
		(fp_line
			(start 0.8636 0.4064)
			(end 1.1938 0.4064)
			(stroke
				(width 0.1)
				(type default)
			)
			(layer "B.Fab")
		)
		(fp_line
			(start -0.8636 0.4064)
			(end -0.8636 0.4572)
			(stroke
				(width 0.1)
				(type default)
			)
			(layer "B.Fab")
		)
		(fp_line
			(start -1.1938 0.4064)
			(end -0.8636 0.4064)
			(stroke
				(width 0.1)
				(type default)
			)
			(layer "B.Fab")
		)
		(fp_line
			(start 0.8636 0.4572)
			(end 0.8636 0.4064)
			(stroke
				(width 0.1)
				(type default)
			)
			(layer "B.Fab")
		)
		(fp_line
			(start -0.8636 0.4572)
			(end 0.8636 0.4572)
			(stroke
				(width 0.1)
				(type default)
			)
			(layer "B.Fab")
		)
		(pad "1" smd rect
			(at 0.7366 0)
			(size 0.7112 0.8128)
			(layers "B.Cu" "B.Mask" "B.Paste")
			(net "P0V8_PEX3")
		)
		(pad "2" smd rect
			(at -0.7366 0)
			(size 0.7112 0.8128)
			(layers "B.Cu" "B.Mask" "B.Paste")
			(net "GND")
		)
	)
	(footprint ""
		(layer "B.Cu")
		(at 170.524932 -293.99992 90)
		(property "Reference" "C1389"
			(at 0 0 90)
			(layer "B.SilkS")
			(hide yes)
			(effects
				(font
					(size 1.27 1.27)
				)
				(justify mirror)
			)
		)
		(property "Value" ""
			(at 0 0 90)
			(layer "B.Fab")
			(effects
				(font
					(size 1.27 1.27)
				)
				(justify mirror)
			)
		)
		(duplicate_pad_numbers_are_jumpers no)
		(fp_line
			(start 0.299974 -0.150114)
			(end -0.299974 -0.150114)
			(stroke
				(width 0.1)
				(type default)
			)
			(layer "B.Fab")
		)
		(fp_line
			(start -0.299974 -0.150114)
			(end -0.299974 0.150114)
			(stroke
				(width 0.1)
				(type default)
			)
			(layer "B.Fab")
		)
		(fp_line
			(start 0.299974 0.150114)
			(end 0.299974 -0.150114)
			(stroke
				(width 0.1)
				(type default)
			)
			(layer "B.Fab")
		)
		(fp_line
			(start -0.299974 0.150114)
			(end 0.299974 0.150114)
			(stroke
				(width 0.1)
				(type default)
			)
			(layer "B.Fab")
		)
		(pad "1" smd rect
			(at 0.2667 0 270)
			(size 0.3048 0.381)
			(layers "B.Cu" "B.Mask" "B.Paste")
			(net "P0V8_PEX1")
		)
		(pad "2" smd rect
			(at -0.2667 0 270)
			(size 0.3048 0.381)
			(layers "B.Cu" "B.Mask" "B.Paste")
			(net "GND")
		)
	)
	(footprint ""
		(layer "B.Cu")
		(at 106.35869 -326.152256 -90)
		(property "Reference" "R1225"
			(at 0 0 90)
			(layer "B.SilkS")
			(hide yes)
			(effects
				(font
					(size 1.27 1.27)
				)
				(justify mirror)
			)
		)
		(property "Value" ""
			(at 0 0 90)
			(layer "B.Fab")
			(effects
				(font
					(size 1.27 1.27)
				)
				(justify mirror)
			)
		)
		(duplicate_pad_numbers_are_jumpers no)
		(fp_line
			(start -0.7874 0.4064)
			(end 0.7874 0.4064)
			(stroke
				(width 0.1524)
				(type default)
			)
			(layer "B.SilkS")
		)
		(fp_line
			(start 0.7874 0.4064)
			(end 0.7874 -0.4064)
			(stroke
				(width 0.1524)
				(type default)
			)
			(layer "B.SilkS")
		)
		(fp_line
			(start -0.7874 -0.4064)
			(end -0.7874 0.4064)
			(stroke
				(width 0.1524)
				(type default)
			)
			(layer "B.SilkS")
		)
		(fp_line
			(start 0.7874 -0.4064)
			(end -0.7874 -0.4064)
			(stroke
				(width 0.1524)
				(type default)
			)
			(layer "B.SilkS")
		)
		(fp_line
			(start -0.67945 0.3048)
			(end -0.120396 0.3048)
			(stroke
				(width 0.1)
				(type default)
			)
			(layer "B.Fab")
		)
		(fp_line
			(start -0.120396 0.3048)
			(end -0.120396 0.2794)
			(stroke
				(width 0.1)
				(type default)
			)
			(layer "B.Fab")
		)
		(fp_line
			(start 0.12065 0.3048)
			(end 0.67945 0.3048)
			(stroke
				(width 0.1)
				(type default)
			)
			(layer "B.Fab")
		)
		(fp_line
			(start 0.67945 0.3048)
			(end 0.67945 -0.305054)
			(stroke
				(width 0.1)
				(type default)
			)
			(layer "B.Fab")
		)
		(fp_line
			(start -0.120396 0.2794)
			(end 0.12065 0.2794)
			(stroke
				(width 0.1)
				(type default)
			)
			(layer "B.Fab")
		)
		(fp_line
			(start 0.12065 0.2794)
			(end 0.12065 0.3048)
			(stroke
				(width 0.1)
				(type default)
			)
			(layer "B.Fab")
		)
		(fp_line
			(start -0.12065 -0.2794)
			(end -0.12065 -0.3048)
			(stroke
				(width 0.1)
				(type default)
			)
			(layer "B.Fab")
		)
		(fp_line
			(start 0.12065 -0.2794)
			(end -0.12065 -0.2794)
			(stroke
				(width 0.1)
				(type default)
			)
			(layer "B.Fab")
		)
		(fp_line
			(start -0.67945 -0.3048)
			(end -0.67945 0.3048)
			(stroke
				(width 0.1)
				(type default)
			)
			(layer "B.Fab")
		)
		(fp_line
			(start -0.12065 -0.3048)
			(end -0.67945 -0.3048)
			(stroke
				(width 0.1)
				(type default)
			)
			(layer "B.Fab")
		)
		(fp_line
			(start 0.12065 -0.305054)
			(end 0.12065 -0.2794)
			(stroke
				(width 0.1)
				(type default)
			)
			(layer "B.Fab")
		)
		(fp_line
			(start 0.67945 -0.305054)
			(end 0.12065 -0.305054)
			(stroke
				(width 0.1)
				(type default)
			)
			(layer "B.Fab")
		)
		(pad "1" smd circle
			(at 0.40005 0 90)
			(size 0 0)
			(layers "B.Cu" "B.Mask" "B.Paste")
			(net "CLK_100M_DB800ZL_PEX0_S0_R_DP")
		)
		(pad "2" smd circle
			(at -0.40005 0 90)
			(size 0 0)
			(layers "B.Cu" "B.Mask" "B.Paste")
			(net "CLK_100M_DB800ZL_PEX0_S0_DP")
		)
	)
)
